# BASEBOARD_FAB2 (Tioga Pass) — schematic netlist excerpt (pin names and nets, part order shuffled) for the footprints in the layout excerpt that follows; sources: Cadence DE-HDL packaged netlist, KiCad conversion of Wiwynn_Tioga_Pass_MB.brd

R25W98  RES  4.75K 1% EMPTY  pkg 0402  page 150 : A = P3V3_STBY ; B = BMC_STRAP_BIT3
C22W5  SC22U16V5MX-4-GP  20%  pkg SMD-BCG5  page 234 : \1\ = VR_FET_SW_P12V_STBY_PVPP_KLM ; \2\ = GND
C9N25  CAP  10UF 16V 10% X6S  pkg 0805  page 209 : A = VR_FET_SW_P12V_STBY_PVCCIN_CPU1 ; B = GND

(kicad_pcb
	(version 20260206)
	(generator "pcbnew")
	(generator_version "10.0")
	(general
		(thickness 1.6)
		(legacy_teardrops no)
	)
	(paper "A4")
	(title_block
		(title "Wiwynn_Tioga_Pass_MB.brd")
		(comment 1 "Tioga Pass / footprints 2816-2818 of 4770")
	)
	(layers
		(0 "F.Cu" signal "TOP")
		(4 "In1.Cu" signal "L2GND")
		(6 "In2.Cu" signal "L3")
		(8 "In3.Cu" signal "L4GND")
		(10 "In4.Cu" signal "L5")
		(12 "In5.Cu" signal "L6GND")
		(14 "In6.Cu" signal "L7VCC")
		(16 "In7.Cu" signal "L8VCC")
		(18 "In8.Cu" signal "L9GND")
		(20 "In9.Cu" signal "L10")
		(22 "In10.Cu" signal "L11GND")
		(24 "In11.Cu" signal "L12")
		(26 "In12.Cu" signal "L13GND")
		(2 "B.Cu" signal "BOTTOM")
		(9 "F.Adhes" user "F.Adhesive")
		(11 "B.Adhes" user "B.Adhesive")
		(13 "F.Paste" user "Package Geometry/Pastemask Top")
		(15 "B.Paste" user "Package Geometry/Pastemask Bottom")
		(5 "F.SilkS" user "Ref Des/Silkscreen Top")
		(7 "B.SilkS" user "Ref Des/Silkscreen Bottom")
		(1 "F.Mask" user "Board Geometry/Soldermask Top")
		(3 "B.Mask" user "Board Geometry/Soldermask Bottom")
		(17 "Dwgs.User" user "User.Drawings")
		(19 "Cmts.User" user "User.Comments")
		(21 "Eco1.User" user "User.Eco1")
		(23 "Eco2.User" user "User.Eco2")
		(25 "Edge.Cuts" user "Board Geometry/Outline")
		(27 "Margin" user)
		(31 "F.CrtYd" user "Package Geometry/Place Bound Top")
		(29 "B.CrtYd" user "Package Geometry/Place Bound Bottom")
		(35 "F.Fab" user "Ref Des/Assembly Top")
		(33 "B.Fab" user "Ref Des/Assembly Bottom")
	)
	(footprint ""
		(layer "B.Cu")
		(at 32.832802 -92.485464 90)
		(property "Reference" "C9N25"
			(at 0 0 90)
			(layer "B.SilkS")
			(hide yes)
			(effects
				(font
					(size 1.27 1.27)
				)
				(justify mirror)
			)
		)
		(property "Value" ""
			(at 0 0 90)
			(layer "B.Fab")
			(effects
				(font
					(size 1.27 1.27)
				)
				(justify mirror)
			)
		)
		(duplicate_pad_numbers_are_jumpers no)
		(fp_poly
			(pts
				(xy 0.7239 -0.2159) (xy -0.7239 -0.2159) (xy -0.7239 1.9939) (xy 0.7239 1.9939)
			)
			(stroke
				(width 0)
				(type default)
			)
			(fill no)
			(layer "B.CrtYd")
		)
		(fp_line
			(start 0.7239 -0.2159)
			(end 0.7239 1.9939)
			(stroke
				(width 0.1)
				(type default)
			)
			(layer "B.Fab")
		)
		(fp_line
			(start -0.7239 -0.2159)
			(end 0.7239 -0.2159)
			(stroke
				(width 0.1)
				(type default)
			)
			(layer "B.Fab")
		)
		(fp_line
			(start 0.7239 1.9939)
			(end -0.7239 1.9939)
			(stroke
				(width 0.1)
				(type default)
			)
			(layer "B.Fab")
		)
		(fp_line
			(start -0.7239 1.9939)
			(end -0.7239 -0.2159)
			(stroke
				(width 0.1)
				(type default)
			)
			(layer "B.Fab")
		)
		(pad "1" smd rect
			(at 0 0 270)
			(size 1.27 1.016)
			(layers "B.Cu" "B.Mask" "B.Paste")
			(net "VR_FET_SW_P12V_STBY_PVCCIN_CPU1")
		)
		(pad "2" smd rect
			(at 0 1.778 270)
			(size 1.27 1.016)
			(layers "B.Cu" "B.Mask" "B.Paste")
			(net "GND")
		)
		(zone
			(layer "B.Cu")
			(hatch none 0.5)
			(connect_pads
				(clearance 0)
			)
			(min_thickness 0.25)
			(keepout
				(tracks not_allowed)
				(vias allowed)
				(pads allowed)
				(copperpour not_allowed)
				(footprints allowed)
			)
			(placement
				(enabled no)
				(sheetname "")
			)
			(fill
				(thermal_gap 0.5)
				(thermal_bridge_width 0.5)
				(island_removal_mode 0)
			)
			(polygon
				(pts
					(xy 33.340802 -93.120464) (xy 33.340802 -91.850464) (xy 34.102802 -91.850464) (xy 34.102802 -93.120464)
				)
			)
		)
	)
	(footprint ""
		(layer "B.Cu")
		(at 418.680646 -45.539152)
		(property "Reference" "R25W98"
			(at 0.8382 -0.67818 0)
			(unlocked yes)
			(layer "B.SilkS")
			(effects
				(font
					(size 0.4064 0.254)
					(thickness 0.1524)
				)
				(justify left mirror)
			)
		)
		(property "Value" ""
			(at 0 0 0)
			(layer "B.Fab")
			(effects
				(font
					(size 1.27 1.27)
				)
				(justify mirror)
			)
		)
		(duplicate_pad_numbers_are_jumpers no)
		(fp_poly
			(pts
				(xy 0.2794 -0.1016) (xy -0.2794 -0.1016) (xy -0.2794 0.9906) (xy 0.2794 0.9906)
			)
			(stroke
				(width 0)
				(type default)
			)
			(fill no)
			(layer "B.CrtYd")
		)
		(fp_line
			(start -0.2794 -0.1016)
			(end 0.2794 -0.1016)
			(stroke
				(width 0.1)
				(type default)
			)
			(layer "B.Fab")
		)
		(fp_line
			(start -0.2794 0.9906)
			(end -0.2794 -0.1016)
			(stroke
				(width 0.1)
				(type default)
			)
			(layer "B.Fab")
		)
		(fp_line
			(start 0.2794 -0.1016)
			(end 0.2794 0.9906)
			(stroke
				(width 0.1)
				(type default)
			)
			(layer "B.Fab")
		)
		(fp_line
			(start 0.2794 0.9906)
			(end -0.2794 0.9906)
			(stroke
				(width 0.1)
				(type default)
			)
			(layer "B.Fab")
		)
		(pad "1" smd rect
			(at 0 0 180)
			(size 0.508 0.508)
			(layers "B.Cu" "B.Mask" "B.Paste")
			(net "P3V3_STBY")
		)
		(pad "2" smd rect
			(at 0 0.889 180)
			(size 0.508 0.508)
			(layers "B.Cu" "B.Mask" "B.Paste")
			(net "BMC_STRAP_BIT3")
		)
		(zone
			(layer "B.Cu")
			(hatch none 0.5)
			(connect_pads
				(clearance 0)
			)
			(min_thickness 0.25)
			(keepout
				(tracks allowed)
				(vias not_allowed)
				(pads allowed)
				(copperpour not_allowed)
				(footprints allowed)
			)
			(placement
				(enabled no)
				(sheetname "")
			)
			(fill
				(thermal_gap 0.5)
				(thermal_bridge_width 0.5)
				(island_removal_mode 0)
			)
			(polygon
				(pts
					(xy 418.934646 -45.285152) (xy 418.426646 -45.285152) (xy 418.426646 -44.904152) (xy 418.934646 -44.904152)
				)
			)
		)
		(zone
			(layer "B.Cu")
			(hatch none 0.5)
			(connect_pads
				(clearance 0)
			)
			(min_thickness 0.25)
			(keepout
				(tracks not_allowed)
				(vias allowed)
				(pads allowed)
				(copperpour not_allowed)
				(footprints allowed)
			)
			(placement
				(enabled no)
				(sheetname "")
			)
			(fill
				(thermal_gap 0.5)
				(thermal_bridge_width 0.5)
				(island_removal_mode 0)
			)
			(polygon
				(pts
					(xy 418.934646 -44.904152) (xy 418.426646 -44.904152) (xy 418.426646 -45.285152) (xy 418.934646 -45.285152)
				)
			)
		)
	)
	(footprint ""
		(layer "B.Cu")
		(at 184.0484 -132.842 90)
		(property "Reference" "C22W5"
			(at 0 0 90)
			(layer "B.SilkS")
			(hide yes)
			(effects
				(font
					(size 1.27 1.27)
				)
				(justify mirror)
			)
		)
		(property "Value" "*"
			(at 0.0762 -6.2357 90)
			(unlocked yes)
			(layer "B.Fab")
			(hide yes)
			(effects
				(font
					(size 1.27 1.016)
					(thickness 0.1524)
				)
				(justify mirror)
			)
		)
		(property "Device Type" "SC22U16V5MX-4-GP_SMD-BCG5-SC22A"
			(at 0.0762 -8.2677 90)
			(unlocked yes)
			(layer "B.Fab")
			(hide yes)
			(effects
				(font
					(size 1.27 1.016)
					(thickness 0.1524)
				)
				(justify mirror)
			)
		)
		(duplicate_pad_numbers_are_jumpers no)
		(fp_line
			(start -0.635 0)
			(end 0.635 0)
			(stroke
				(width 0.508)
				(type default)
			)
			(layer "B.SilkS")
		)
		(fp_rect
			(start 0.9652 1.778)
			(end -0.9652 -1.778)
			(stroke
				(width 0)
				(type default)
			)
			(fill no)
			(layer "B.CrtYd")
		)
		(fp_poly
			(pts
				(xy 0.9652 -1.778) (xy -0.9652 -1.778) (xy -0.9652 1.778) (xy 0.9652 1.778)
			)
			(stroke
				(width 0)
				(type default)
			)
			(fill no)
			(layer "B.Fab")
		)
		(pad "1" smd rect
			(at 0 -0.9652 270)
			(size 1.397 1.143)
			(layers "B.Cu" "B.Mask" "B.Paste")
			(net "VR_FET_SW_P12V_STBY_PVPP_KLM")
		)
		(pad "2" smd rect
			(at 0 0.9652 270)
			(size 1.397 1.143)
			(layers "B.Cu" "B.Mask" "B.Paste")
			(net "GND")
		)
	)
)
